#ISCELL
  mstr_misc dns *
  *
#ISCELL
  mstr_symbols bom_note *
  *
#ISCELL
  mstr_symbols design_note *
  *
#ISCELL
  mstr_symbols intel_corp_bpage *
  *
#ISCELL
  mstr_standard offpage *
  page189_i1
#ISCELL
  mstr_standard offpage *
  page189_i10
#ISCELL
  mstr_standard offpage *
  page189_i11
#ISCELL
  mstr_standard offpage *
  page189_i12
#CELL
  mstr_discrete res *
  page189_i13
#ISCELL
  mstr_standard offpage *
  page189_i14
#ISCELL
  mstr_standard offpage *
  page189_i15
#ISCELL
  mstr_standard offpage *
  page189_i16
#CELL
  mstr_discrete res *
  page189_i17
#CELL
  mstr_discrete res *
  page189_i18
#CELL
  mstr_discrete res *
  page189_i19
#ISCELL
  mstr_standard offpage *
  page189_i2
#CELL
  mstr_discrete res *
  page189_i20
#CELL
  mstr_discrete res *
  page189_i21
#CELL
  mstr_discrete res *
  page189_i22
#CELL
  mstr_discrete res *
  page189_i23
#CELL
  mstr_discrete res *
  page189_i24
#CELL
  mstr_discrete res *
  page189_i25
#CELL
  mstr_discrete res *
  page189_i26
#CELL
  mstr_discrete res *
  page189_i27
#ISCELL
  mstr_standard offpage *
  page189_i28
#ISCELL
  mstr_standard offpage *
  page189_i29
#ISCELL
  mstr_standard offpage *
  page189_i3
#ISCELL
  mstr_standard offpage *
  page189_i30
#ISCELL
  mstr_standard offpage *
  page189_i31
#ISCELL
  mstr_standard offpage *
  page189_i32
#ISCELL
  mstr_standard offpage *
  page189_i33
#ISCELL
  mstr_standard offpage *
  page189_i34
#ISCELL
  mstr_standard offpage *
  page189_i35
#CELL
  mstr_discrete res *
  page189_i36
#CELL
  mstr_discrete res *
  page189_i37
#CELL
  mstr_discrete res *
  page189_i38
#ISCELL
  mstr_standard offpage *
  page189_i39
#ISCELL
  mstr_standard offpage *
  page189_i4
#ISCELL
  mstr_standard offpage *
  page189_i40
#ISCELL
  mstr_standard offpage *
  page189_i41
#ISCELL
  mstr_standard offpage *
  page189_i42
#ISCELL
  mstr_symbols p3v3_stby *
  page189_i43
#CELL
  mstr_discrete res *
  page189_i44
#CELL
  mstr_discrete res *
  page189_i45
#ISCELL
  mstr_symbols gnd *
  page189_i46
#CELL
  mstr_conn conn8_c77962004 *
  page189_i47
#ISCELL
  mstr_symbols p3v3_stby *
  page189_i48
#CELL
  mstr_discrete diode *
  page189_i49
#ISCELL
  mstr_standard offpage *
  page189_i5
#CELL
  mstr_discrete res *
  page189_i50
#CELL
  mstr_discrete res *
  page189_i51
#ISCELL
  mstr_symbols p3v3_stby *
  page189_i52
#CELL
  mstr_discrete res *
  page189_i53
#ISCELL
  mstr_symbols gnd *
  page189_i54
#ISCELL
  mstr_symbols gnd *
  page189_i55
#CELL
  mstr_discrete res *
  page189_i56
#ISCELL
  mstr_standard offpage *
  page189_i57
#ISCELL
  mstr_standard offpage *
  page189_i58
#ISCELL
  mstr_standard offpage *
  page189_i59
#ISCELL
  mstr_standard offpage *
  page189_i6
#ISCELL
  mstr_standard offpage *
  page189_i60
#ISCELL
  mstr_standard offpage *
  page189_i61
#ISCELL
  mstr_standard offpage *
  page189_i62
#CELL
  mstr_discrete res *
  page189_i63
#CELL
  mstr_discrete res *
  page189_i64
#CELL
  mstr_discrete res *
  page189_i65
#CELL
  mstr_discrete res *
  page189_i66
#CELL
  mstr_discrete res *
  page189_i7
#CELL
  mstr_discrete res *
  page189_i8
#CELL
  mstr_discrete res *
  page189_i9
